# T6G (Grand Teton) — schematic netlist excerpt (pin names and nets, part order shuffled) for the footprints in the layout excerpt that follows; sources: Cadence DE-HDL packaged netlist, KiCad conversion of 04192023_DAF0TMB3IC0_F0TG_MB_C_brd_V02_OCP.brd

R5020  Q_RES  1K 1% EMPTY  pkg 0402LF  page 159 : A = PVDD11_S3_P1 ; B = I3C_SCM_3_R_SCL
C3898  Q_CAP  22UF 4V 20% X6S  pkg C0402  page 68 : A = PVDDIO_P0 ; B = GND

(kicad_pcb
	(version 20260206)
	(generator "pcbnew")
	(generator_version "10.0")
	(general
		(thickness 1.6)
		(legacy_teardrops no)
	)
	(paper "A4")
	(title_block
		(title "04192023_DAF0TMB3IC0_F0TG_MB_C_brd_V02_OCP.brd")
		(comment 1 "Grand Teton / footprints 2063-2064 of 8354")
	)
	(layers
		(0 "F.Cu" signal "TOP")
		(4 "In1.Cu" signal "GND")
		(6 "In2.Cu" signal "IN1")
		(8 "In3.Cu" signal "GND1")
		(10 "In4.Cu" signal "IN2")
		(12 "In5.Cu" signal "GND2")
		(14 "In6.Cu" signal "IN3")
		(16 "In7.Cu" signal "GND3")
		(18 "In8.Cu" signal "VCC")
		(20 "In9.Cu" signal "VCC1")
		(22 "In10.Cu" signal "GND4")
		(24 "In11.Cu" signal "IN4")
		(26 "In12.Cu" signal "GND5")
		(28 "In13.Cu" signal "IN5")
		(30 "In14.Cu" signal "GND6")
		(32 "In15.Cu" signal "IN6")
		(34 "In16.Cu" signal "GND7")
		(2 "B.Cu" signal "BOTTOM")
		(9 "F.Adhes" user "F.Adhesive")
		(11 "B.Adhes" user "B.Adhesive")
		(13 "F.Paste" user "Package Geometry/Pastemask Top")
		(15 "B.Paste" user "Package Geometry/Pastemask Bottom")
		(5 "F.SilkS" user "Ref Des/Silkscreen Top")
		(7 "B.SilkS" user "Ref Des/Silkscreen Bottom")
		(1 "F.Mask" user "Board Geometry/Soldermask Top")
		(3 "B.Mask" user "Board Geometry/Soldermask Bottom")
		(17 "Dwgs.User" user "User.Drawings")
		(19 "Cmts.User" user "User.Comments")
		(21 "Eco1.User" user "User.Eco1")
		(23 "Eco2.User" user "User.Eco2")
		(25 "Edge.Cuts" user "Board Geometry/Outline")
		(27 "Margin" user)
		(31 "F.CrtYd" user "Package Geometry/Place Bound Top")
		(29 "B.CrtYd" user "Package Geometry/Place Bound Bottom")
		(35 "F.Fab" user "Ref Des/Assembly Top")
		(33 "B.Fab" user "Ref Des/Assembly Bottom")
	)
	(footprint ""
		(layer "F.Cu")
		(at 356.29596 -259.845048)
		(property "Reference" "C3898"
			(at 0 0 0)
			(layer "F.SilkS")
			(hide yes)
			(effects
				(font
					(size 1.27 1.27)
				)
			)
		)
		(property "Value" ""
			(at 0 0 0)
			(layer "F.Fab")
			(effects
				(font
					(size 1.27 1.27)
				)
			)
		)
		(duplicate_pad_numbers_are_jumpers no)
		(fp_line
			(start -0.7874 -0.4064)
			(end 0.7874 -0.4064)
			(stroke
				(width 0.1524)
				(type default)
			)
			(layer "F.SilkS")
		)
		(fp_line
			(start -0.7874 0.4064)
			(end -0.7874 -0.4064)
			(stroke
				(width 0.1524)
				(type default)
			)
			(layer "F.SilkS")
		)
		(fp_line
			(start 0.7874 -0.4064)
			(end 0.7874 0.4064)
			(stroke
				(width 0.1524)
				(type default)
			)
			(layer "F.SilkS")
		)
		(fp_line
			(start 0.7874 0.4064)
			(end -0.7874 0.4064)
			(stroke
				(width 0.1524)
				(type default)
			)
			(layer "F.SilkS")
		)
		(fp_line
			(start -0.67945 -0.305054)
			(end -0.12065 -0.305054)
			(stroke
				(width 0.1)
				(type default)
			)
			(layer "F.Fab")
		)
		(fp_line
			(start -0.67945 0.3048)
			(end -0.67945 -0.305054)
			(stroke
				(width 0.1)
				(type default)
			)
			(layer "F.Fab")
		)
		(fp_line
			(start -0.12065 -0.305054)
			(end -0.12065 -0.2794)
			(stroke
				(width 0.1)
				(type default)
			)
			(layer "F.Fab")
		)
		(fp_line
			(start -0.12065 -0.2794)
			(end 0.12065 -0.2794)
			(stroke
				(width 0.1)
				(type default)
			)
			(layer "F.Fab")
		)
		(fp_line
			(start -0.12065 0.2794)
			(end -0.12065 0.3048)
			(stroke
				(width 0.1)
				(type default)
			)
			(layer "F.Fab")
		)
		(fp_line
			(start -0.12065 0.3048)
			(end -0.67945 0.3048)
			(stroke
				(width 0.1)
				(type default)
			)
			(layer "F.Fab")
		)
		(fp_line
			(start 0.120396 0.2794)
			(end -0.12065 0.2794)
			(stroke
				(width 0.1)
				(type default)
			)
			(layer "F.Fab")
		)
		(fp_line
			(start 0.120396 0.3048)
			(end 0.120396 0.2794)
			(stroke
				(width 0.1)
				(type default)
			)
			(layer "F.Fab")
		)
		(fp_line
			(start 0.12065 -0.3048)
			(end 0.67945 -0.3048)
			(stroke
				(width 0.1)
				(type default)
			)
			(layer "F.Fab")
		)
		(fp_line
			(start 0.12065 -0.2794)
			(end 0.12065 -0.3048)
			(stroke
				(width 0.1)
				(type default)
			)
			(layer "F.Fab")
		)
		(fp_line
			(start 0.67945 -0.3048)
			(end 0.67945 0.3048)
			(stroke
				(width 0.1)
				(type default)
			)
			(layer "F.Fab")
		)
		(fp_line
			(start 0.67945 0.3048)
			(end 0.120396 0.3048)
			(stroke
				(width 0.1)
				(type default)
			)
			(layer "F.Fab")
		)
		(pad "1" smd circle
			(at -0.40005 0)
			(size 0 0)
			(layers "F.Cu" "F.Mask" "F.Paste")
			(net "PVDDIO_P0")
		)
		(pad "2" smd circle
			(at 0.40005 0)
			(size 0 0)
			(layers "F.Cu" "F.Mask" "F.Paste")
			(net "GND")
		)
	)
	(footprint ""
		(layer "F.Cu")
		(at 182.047134 -160.595818 90)
		(property "Reference" "R5020"
			(at 0 0 90)
			(layer "F.SilkS")
			(hide yes)
			(effects
				(font
					(size 1.27 1.27)
				)
			)
		)
		(property "Value" ""
			(at 0 0 90)
			(layer "F.Fab")
			(effects
				(font
					(size 1.27 1.27)
				)
			)
		)
		(duplicate_pad_numbers_are_jumpers no)
		(fp_line
			(start 0.7874 -0.4064)
			(end 0.7874 0.4064)
			(stroke
				(width 0.1524)
				(type default)
			)
			(layer "F.SilkS")
		)
		(fp_line
			(start -0.7874 -0.4064)
			(end 0.7874 -0.4064)
			(stroke
				(width 0.1524)
				(type default)
			)
			(layer "F.SilkS")
		)
		(fp_line
			(start 0.7874 0.4064)
			(end -0.7874 0.4064)
			(stroke
				(width 0.1524)
				(type default)
			)
			(layer "F.SilkS")
		)
		(fp_line
			(start -0.7874 0.4064)
			(end -0.7874 -0.4064)
			(stroke
				(width 0.1524)
				(type default)
			)
			(layer "F.SilkS")
		)
		(fp_line
			(start -0.12065 -0.305054)
			(end -0.12065 -0.2794)
			(stroke
				(width 0.1)
				(type default)
			)
			(layer "F.Fab")
		)
		(fp_line
			(start -0.67945 -0.305054)
			(end -0.12065 -0.305054)
			(stroke
				(width 0.1)
				(type default)
			)
			(layer "F.Fab")
		)
		(fp_line
			(start 0.67945 -0.3048)
			(end 0.67945 0.3048)
			(stroke
				(width 0.1)
				(type default)
			)
			(layer "F.Fab")
		)
		(fp_line
			(start 0.12065 -0.3048)
			(end 0.67945 -0.3048)
			(stroke
				(width 0.1)
				(type default)
			)
			(layer "F.Fab")
		)
		(fp_line
			(start 0.12065 -0.2794)
			(end 0.12065 -0.3048)
			(stroke
				(width 0.1)
				(type default)
			)
			(layer "F.Fab")
		)
		(fp_line
			(start -0.12065 -0.2794)
			(end 0.12065 -0.2794)
			(stroke
				(width 0.1)
				(type default)
			)
			(layer "F.Fab")
		)
		(fp_line
			(start 0.120396 0.2794)
			(end -0.12065 0.2794)
			(stroke
				(width 0.1)
				(type default)
			)
			(layer "F.Fab")
		)
		(fp_line
			(start -0.12065 0.2794)
			(end -0.12065 0.3048)
			(stroke
				(width 0.1)
				(type default)
			)
			(layer "F.Fab")
		)
		(fp_line
			(start 0.67945 0.3048)
			(end 0.120396 0.3048)
			(stroke
				(width 0.1)
				(type default)
			)
			(layer "F.Fab")
		)
		(fp_line
			(start 0.120396 0.3048)
			(end 0.120396 0.2794)
			(stroke
				(width 0.1)
				(type default)
			)
			(layer "F.Fab")
		)
		(fp_line
			(start -0.12065 0.3048)
			(end -0.67945 0.3048)
			(stroke
				(width 0.1)
				(type default)
			)
			(layer "F.Fab")
		)
		(fp_line
			(start -0.67945 0.3048)
			(end -0.67945 -0.305054)
			(stroke
				(width 0.1)
				(type default)
			)
			(layer "F.Fab")
		)
		(pad "1" smd circle
			(at -0.40005 0 90)
			(size 0 0)
			(layers "F.Cu" "F.Mask" "F.Paste")
			(net "PVDD11_S3_P1")
		)
		(pad "2" smd circle
			(at 0.40005 0 90)
			(size 0 0)
			(layers "F.Cu" "F.Mask" "F.Paste")
			(net "I3C_SCM_3_R_SCL")
		)
	)
)
